# S9S_MB_2U (Grand Teton) — schematic netlist excerpt (pin names and nets, part order shuffled) for the footprints in the layout excerpt that follows; sources: Cadence DE-HDL packaged netlist, KiCad conversion of 03242023_DA0F0TMBIJ0_F0T_Motherboard_J_brd_V01_OCP.brd

PR444  Q_RES  0 5% CHIP  pkg 0402LF  page 271 : A = P5V ; B = PVCCFA_EHV_FIVRA_CPU0_PVCC1
R1691  Q_RES  10K 1% EMPTY  pkg 0402LF  page 244 : A = P3V3_AUX ; B = PWRGD_DSW_PWROK_R1

(kicad_pcb
	(version 20260206)
	(generator "pcbnew")
	(generator_version "10.0")
	(general
		(thickness 1.6)
		(legacy_teardrops no)
	)
	(paper "A4")
	(title_block
		(title "03242023_DA0F0TMBIJ0_F0T_Motherboard_J_brd_V01_OCP.brd")
		(comment 1 "Grand Teton / footprints 1709-1710 of 6105")
	)
	(layers
		(0 "F.Cu" signal "TOP")
		(4 "In1.Cu" signal "GND")
		(6 "In2.Cu" signal "IN1")
		(8 "In3.Cu" signal "GND1")
		(10 "In4.Cu" signal "IN2")
		(12 "In5.Cu" signal "GND2")
		(14 "In6.Cu" signal "IN3")
		(16 "In7.Cu" signal "GND3")
		(18 "In8.Cu" signal "VCC")
		(20 "In9.Cu" signal "VCC1")
		(22 "In10.Cu" signal "GND4")
		(24 "In11.Cu" signal "IN4")
		(26 "In12.Cu" signal "GND5")
		(28 "In13.Cu" signal "IN5")
		(30 "In14.Cu" signal "GND6")
		(32 "In15.Cu" signal "IN6")
		(34 "In16.Cu" signal "GND7")
		(2 "B.Cu" signal "BOTTOM")
		(9 "F.Adhes" user "F.Adhesive")
		(11 "B.Adhes" user "B.Adhesive")
		(13 "F.Paste" user "Package Geometry/Pastemask Top")
		(15 "B.Paste" user "Package Geometry/Pastemask Bottom")
		(5 "F.SilkS" user "Ref Des/Silkscreen Top")
		(7 "B.SilkS" user "Ref Des/Silkscreen Bottom")
		(1 "F.Mask" user "Board Geometry/Soldermask Top")
		(3 "B.Mask" user "Board Geometry/Soldermask Bottom")
		(17 "Dwgs.User" user "User.Drawings")
		(19 "Cmts.User" user "User.Comments")
		(21 "Eco1.User" user "User.Eco1")
		(23 "Eco2.User" user "User.Eco2")
		(25 "Edge.Cuts" user "Board Geometry/Outline")
		(27 "Margin" user)
		(31 "F.CrtYd" user "Package Geometry/Place Bound Top")
		(29 "B.CrtYd" user "Package Geometry/Place Bound Bottom")
		(35 "F.Fab" user "Ref Des/Assembly Top")
		(33 "B.Fab" user "Ref Des/Assembly Bottom")
	)
	(footprint ""
		(layer "F.Cu")
		(at 411.201108 -363.193584)
		(property "Reference" "PR444"
			(at 0 0 0)
			(layer "F.SilkS")
			(hide yes)
			(effects
				(font
					(size 1.27 1.27)
				)
			)
		)
		(property "Value" ""
			(at 0 0 0)
			(layer "F.Fab")
			(effects
				(font
					(size 1.27 1.27)
				)
			)
		)
		(duplicate_pad_numbers_are_jumpers no)
		(fp_line
			(start -0.7874 -0.4064)
			(end 0.7874 -0.4064)
			(stroke
				(width 0.1524)
				(type default)
			)
			(layer "F.SilkS")
		)
		(fp_line
			(start -0.7874 0.4064)
			(end -0.7874 -0.4064)
			(stroke
				(width 0.1524)
				(type default)
			)
			(layer "F.SilkS")
		)
		(fp_line
			(start 0.7874 -0.4064)
			(end 0.7874 0.4064)
			(stroke
				(width 0.1524)
				(type default)
			)
			(layer "F.SilkS")
		)
		(fp_line
			(start 0.7874 0.4064)
			(end -0.7874 0.4064)
			(stroke
				(width 0.1524)
				(type default)
			)
			(layer "F.SilkS")
		)
		(fp_line
			(start -0.67945 -0.305054)
			(end -0.12065 -0.305054)
			(stroke
				(width 0.1)
				(type default)
			)
			(layer "F.Fab")
		)
		(fp_line
			(start -0.67945 0.3048)
			(end -0.67945 -0.305054)
			(stroke
				(width 0.1)
				(type default)
			)
			(layer "F.Fab")
		)
		(fp_line
			(start -0.12065 -0.305054)
			(end -0.12065 -0.2794)
			(stroke
				(width 0.1)
				(type default)
			)
			(layer "F.Fab")
		)
		(fp_line
			(start -0.12065 -0.2794)
			(end 0.12065 -0.2794)
			(stroke
				(width 0.1)
				(type default)
			)
			(layer "F.Fab")
		)
		(fp_line
			(start -0.12065 0.2794)
			(end -0.12065 0.3048)
			(stroke
				(width 0.1)
				(type default)
			)
			(layer "F.Fab")
		)
		(fp_line
			(start -0.12065 0.3048)
			(end -0.67945 0.3048)
			(stroke
				(width 0.1)
				(type default)
			)
			(layer "F.Fab")
		)
		(fp_line
			(start 0.120396 0.2794)
			(end -0.12065 0.2794)
			(stroke
				(width 0.1)
				(type default)
			)
			(layer "F.Fab")
		)
		(fp_line
			(start 0.120396 0.3048)
			(end 0.120396 0.2794)
			(stroke
				(width 0.1)
				(type default)
			)
			(layer "F.Fab")
		)
		(fp_line
			(start 0.12065 -0.3048)
			(end 0.67945 -0.3048)
			(stroke
				(width 0.1)
				(type default)
			)
			(layer "F.Fab")
		)
		(fp_line
			(start 0.12065 -0.2794)
			(end 0.12065 -0.3048)
			(stroke
				(width 0.1)
				(type default)
			)
			(layer "F.Fab")
		)
		(fp_line
			(start 0.67945 -0.3048)
			(end 0.67945 0.3048)
			(stroke
				(width 0.1)
				(type default)
			)
			(layer "F.Fab")
		)
		(fp_line
			(start 0.67945 0.3048)
			(end 0.120396 0.3048)
			(stroke
				(width 0.1)
				(type default)
			)
			(layer "F.Fab")
		)
		(pad "1" smd circle
			(at -0.40005 0)
			(size 0 0)
			(layers "F.Cu" "F.Mask" "F.Paste")
			(net "P5V")
		)
		(pad "2" smd circle
			(at 0.40005 0)
			(size 0 0)
			(layers "F.Cu" "F.Mask" "F.Paste")
			(net "PVCCFA_EHV_FIVRA_CPU0_PVCC1")
		)
	)
	(footprint ""
		(layer "F.Cu")
		(at 218.08948 -128.819148 180)
		(property "Reference" "R1691"
			(at 0 0 180)
			(layer "F.SilkS")
			(hide yes)
			(effects
				(font
					(size 1.27 1.27)
				)
			)
		)
		(property "Value" ""
			(at 0 0 180)
			(layer "F.Fab")
			(effects
				(font
					(size 1.27 1.27)
				)
			)
		)
		(duplicate_pad_numbers_are_jumpers no)
		(fp_line
			(start 0.7874 0.4064)
			(end -0.7874 0.4064)
			(stroke
				(width 0.1524)
				(type default)
			)
			(layer "F.SilkS")
		)
		(fp_line
			(start 0.7874 -0.4064)
			(end 0.7874 0.4064)
			(stroke
				(width 0.1524)
				(type default)
			)
			(layer "F.SilkS")
		)
		(fp_line
			(start -0.7874 0.4064)
			(end -0.7874 -0.4064)
			(stroke
				(width 0.1524)
				(type default)
			)
			(layer "F.SilkS")
		)
		(fp_line
			(start -0.7874 -0.4064)
			(end 0.7874 -0.4064)
			(stroke
				(width 0.1524)
				(type default)
			)
			(layer "F.SilkS")
		)
		(fp_line
			(start 0.67945 0.3048)
			(end 0.120396 0.3048)
			(stroke
				(width 0.1)
				(type default)
			)
			(layer "F.Fab")
		)
		(fp_line
			(start 0.67945 -0.3048)
			(end 0.67945 0.3048)
			(stroke
				(width 0.1)
				(type default)
			)
			(layer "F.Fab")
		)
		(fp_line
			(start 0.12065 -0.2794)
			(end 0.12065 -0.3048)
			(stroke
				(width 0.1)
				(type default)
			)
			(layer "F.Fab")
		)
		(fp_line
			(start 0.12065 -0.3048)
			(end 0.67945 -0.3048)
			(stroke
				(width 0.1)
				(type default)
			)
			(layer "F.Fab")
		)
		(fp_line
			(start 0.120396 0.3048)
			(end 0.120396 0.2794)
			(stroke
				(width 0.1)
				(type default)
			)
			(layer "F.Fab")
		)
		(fp_line
			(start 0.120396 0.2794)
			(end -0.12065 0.2794)
			(stroke
				(width 0.1)
				(type default)
			)
			(layer "F.Fab")
		)
		(fp_line
			(start -0.12065 0.3048)
			(end -0.67945 0.3048)
			(stroke
				(width 0.1)
				(type default)
			)
			(layer "F.Fab")
		)
		(fp_line
			(start -0.12065 0.2794)
			(end -0.12065 0.3048)
			(stroke
				(width 0.1)
				(type default)
			)
			(layer "F.Fab")
		)
		(fp_line
			(start -0.12065 -0.2794)
			(end 0.12065 -0.2794)
			(stroke
				(width 0.1)
				(type default)
			)
			(layer "F.Fab")
		)
		(fp_line
			(start -0.12065 -0.305054)
			(end -0.12065 -0.2794)
			(stroke
				(width 0.1)
				(type default)
			)
			(layer "F.Fab")
		)
		(fp_line
			(start -0.67945 0.3048)
			(end -0.67945 -0.305054)
			(stroke
				(width 0.1)
				(type default)
			)
			(layer "F.Fab")
		)
		(fp_line
			(start -0.67945 -0.305054)
			(end -0.12065 -0.305054)
			(stroke
				(width 0.1)
				(type default)
			)
			(layer "F.Fab")
		)
		(pad "1" smd circle
			(at -0.40005 0 180)
			(size 0 0)
			(layers "F.Cu" "F.Mask" "F.Paste")
			(net "P3V3_AUX")
		)
		(pad "2" smd circle
			(at 0.40005 0 180)
			(size 0 0)
			(layers "F.Cu" "F.Mask" "F.Paste")
			(net "PWRGD_DSW_PWROK_R1")
		)
	)
)
